(kicad_pcb
	(version 20260206)
	(generator "pcbnew")
	(generator_version "10.0")
	(general
		(thickness 1.6)
		(legacy_teardrops no)
	)
	(paper "A4")
	(title_block
		(title "03242023_DA0F0TMBIJ0_F0T_Motherboard_J_brd_V01_OCP.brd")
		(comment 1 "Grand Teton / footprint 1607 of 6105 (J10), pads 1-112 of 291")
	)
	(layers
		(0 "F.Cu" signal "TOP")
		(4 "In1.Cu" signal "GND")
		(6 "In2.Cu" signal "IN1")
		(8 "In3.Cu" signal "GND1")
		(10 "In4.Cu" signal "IN2")
		(12 "In5.Cu" signal "GND2")
		(14 "In6.Cu" signal "IN3")
		(16 "In7.Cu" signal "GND3")
		(18 "In8.Cu" signal "VCC")
		(20 "In9.Cu" signal "VCC1")
		(22 "In10.Cu" signal "GND4")
		(24 "In11.Cu" signal "IN4")
		(26 "In12.Cu" signal "GND5")
		(28 "In13.Cu" signal "IN5")
		(30 "In14.Cu" signal "GND6")
		(32 "In15.Cu" signal "IN6")
		(34 "In16.Cu" signal "GND7")
		(2 "B.Cu" signal "BOTTOM")
		(9 "F.Adhes" user "F.Adhesive")
		(11 "B.Adhes" user "B.Adhesive")
		(13 "F.Paste" user "Package Geometry/Pastemask Top")
		(15 "B.Paste" user "Package Geometry/Pastemask Bottom")
		(5 "F.SilkS" user "Ref Des/Silkscreen Top")
		(7 "B.SilkS" user "Ref Des/Silkscreen Bottom")
		(1 "F.Mask" user "Board Geometry/Soldermask Top")
		(3 "B.Mask" user "Board Geometry/Soldermask Bottom")
		(17 "Dwgs.User" user "User.Drawings")
		(19 "Cmts.User" user "User.Comments")
		(21 "Eco1.User" user "User.Eco1")
		(23 "Eco2.User" user "User.Eco2")
		(25 "Edge.Cuts" user "Board Geometry/Outline")
		(27 "Margin" user)
		(31 "F.CrtYd" user "Package Geometry/Place Bound Top")
		(29 "B.CrtYd" user "Package Geometry/Place Bound Bottom")
		(35 "F.Fab" user "Ref Des/Assembly Top")
		(33 "B.Fab" user "Ref Des/Assembly Bottom")
	)
	(footprint ""
		(layer "F.Cu")
		(at 408.803348 -258.091686)
		(property "Reference" "J10"
			(at -3.683 -81.702148 0)
			(unlocked yes)
			(layer "F.SilkS")
			(effects
				(font
					(size 0.7874 0.5842)
					(thickness 0.1524)
				)
				(justify left)
			)
		)
		(property "Value" ""
			(at 0 0 0)
			(layer "F.Fab")
			(effects
				(font
					(size 1.27 1.27)
				)
			)
		)
		(duplicate_pad_numbers_are_jumpers no)
		(pad "1" smd rect
			(at -2.050034 -63.324994 270)
			(size 0.519938 1.4986)
			(layers "F.Cu" "F.Mask" "F.Paste")
			(net "P12V_S3_AUX_CPU0_NVDIMM")
		)
		(pad "2" smd rect
			(at -2.050034 -62.47511 270)
			(size 0.519938 1.4986)
			(layers "F.Cu" "F.Mask" "F.Paste")
			(net "TP_CHE_CPU0_DIMM2_FRU_0")
		)
		(pad "3" smd rect
			(at -2.050034 -61.624972 270)
			(size 0.519938 1.4986)
			(layers "F.Cu" "F.Mask" "F.Paste")
			(net "P3V3_AUX")
		)
		(pad "4" smd rect
			(at -2.050034 -60.775088 270)
			(size 0.519938 1.4986)
			(layers "F.Cu" "F.Mask" "F.Paste")
			(net "I3C_SPD_DDREFGH_CPU0_LVC1_SCL_1")
		)
		(pad "5" smd rect
			(at -2.050034 -59.92495 270)
			(size 0.519938 1.4986)
			(layers "F.Cu" "F.Mask" "F.Paste")
			(net "I3C_SPD_DDREFGH_CPU0_LVC1_SDA")
		)
		(pad "6" smd rect
			(at -2.050034 -59.075066 270)
			(size 0.519938 1.4986)
			(layers "F.Cu" "F.Mask" "F.Paste")
			(net "GND")
		)
		(pad "7" smd rect
			(at -2.050034 -58.224928 270)
			(size 0.519938 1.4986)
			(layers "F.Cu" "F.Mask" "F.Paste")
			(net "M_E_CPU0_SA_DQ<0>")
		)
		(pad "8" smd rect
			(at -2.050034 -57.375044 270)
			(size 0.519938 1.4986)
			(layers "F.Cu" "F.Mask" "F.Paste")
			(net "GND")
		)
		(pad "9" smd rect
			(at -2.050034 -56.524906 270)
			(size 0.519938 1.4986)
			(layers "F.Cu" "F.Mask" "F.Paste")
			(net "M_E_CPU0_SA_DQ<1>")
		)
		(pad "10" smd rect
			(at -2.050034 -55.675022 270)
			(size 0.519938 1.4986)
			(layers "F.Cu" "F.Mask" "F.Paste")
			(net "GND")
		)
		(pad "11" smd rect
			(at -2.050034 -54.824884 270)
			(size 0.519938 1.4986)
			(layers "F.Cu" "F.Mask" "F.Paste")
			(net "M_E_CPU0_SA_DQS_DP<0>")
		)
		(pad "12" smd rect
			(at -2.050034 -53.975 270)
			(size 0.519938 1.4986)
			(layers "F.Cu" "F.Mask" "F.Paste")
			(net "M_E_CPU0_SA_DQS_DN<0>")
		)
		(pad "13" smd rect
			(at -2.050034 -53.125116 270)
			(size 0.519938 1.4986)
			(layers "F.Cu" "F.Mask" "F.Paste")
			(net "GND")
		)
		(pad "14" smd rect
			(at -2.050034 -52.274978 270)
			(size 0.519938 1.4986)
			(layers "F.Cu" "F.Mask" "F.Paste")
			(net "M_E_CPU0_SA_DQ<4>")
		)
		(pad "15" smd rect
			(at -2.050034 -51.425094 270)
			(size 0.519938 1.4986)
			(layers "F.Cu" "F.Mask" "F.Paste")
			(net "GND")
		)
		(pad "16" smd rect
			(at -2.050034 -50.574956 270)
			(size 0.519938 1.4986)
			(layers "F.Cu" "F.Mask" "F.Paste")
			(net "M_E_CPU0_SA_DQ<5>")
		)
		(pad "17" smd rect
			(at -2.050034 -49.725072 270)
			(size 0.519938 1.4986)
			(layers "F.Cu" "F.Mask" "F.Paste")
			(net "GND")
		)
		(pad "18" smd rect
			(at -2.050034 -48.874934 270)
			(size 0.519938 1.4986)
			(layers "F.Cu" "F.Mask" "F.Paste")
			(net "M_E_CPU0_SA_DQ<8>")
		)
		(pad "19" smd rect
			(at -2.050034 -48.02505 270)
			(size 0.519938 1.4986)
			(layers "F.Cu" "F.Mask" "F.Paste")
			(net "GND")
		)
		(pad "20" smd rect
			(at -2.050034 -47.174912 270)
			(size 0.519938 1.4986)
			(layers "F.Cu" "F.Mask" "F.Paste")
			(net "M_E_CPU0_SA_DQ<9>")
		)
		(pad "21" smd rect
			(at -2.050034 -46.325028 270)
			(size 0.519938 1.4986)
			(layers "F.Cu" "F.Mask" "F.Paste")
			(net "GND")
		)
		(pad "22" smd rect
			(at -2.050034 -45.47489 270)
			(size 0.519938 1.4986)
			(layers "F.Cu" "F.Mask" "F.Paste")
			(net "M_E_CPU0_SA_DQS_DP<1>")
		)
		(pad "23" smd rect
			(at -2.050034 -44.625006 270)
			(size 0.519938 1.4986)
			(layers "F.Cu" "F.Mask" "F.Paste")
			(net "M_E_CPU0_SA_DQS_DN<1>")
		)
		(pad "24" smd rect
			(at -2.050034 -43.775122 270)
			(size 0.519938 1.4986)
			(layers "F.Cu" "F.Mask" "F.Paste")
			(net "GND")
		)
		(pad "25" smd rect
			(at -2.050034 -42.924984 270)
			(size 0.519938 1.4986)
			(layers "F.Cu" "F.Mask" "F.Paste")
			(net "M_E_CPU0_SA_DQ<12>")
		)
		(pad "26" smd rect
			(at -2.050034 -42.0751 270)
			(size 0.519938 1.4986)
			(layers "F.Cu" "F.Mask" "F.Paste")
			(net "GND")
		)
		(pad "27" smd rect
			(at -2.050034 -41.224962 270)
			(size 0.519938 1.4986)
			(layers "F.Cu" "F.Mask" "F.Paste")
			(net "M_E_CPU0_SA_DQ<13>")
		)
		(pad "28" smd rect
			(at -2.050034 -40.375078 270)
			(size 0.519938 1.4986)
			(layers "F.Cu" "F.Mask" "F.Paste")
			(net "GND")
		)
		(pad "29" smd rect
			(at -2.050034 -39.52494 270)
			(size 0.519938 1.4986)
			(layers "F.Cu" "F.Mask" "F.Paste")
			(net "M_E_CPU0_SA_DQ<16>")
		)
		(pad "30" smd rect
			(at -2.050034 -38.675056 270)
			(size 0.519938 1.4986)
			(layers "F.Cu" "F.Mask" "F.Paste")
			(net "GND")
		)
		(pad "31" smd rect
			(at -2.050034 -37.824918 270)
			(size 0.519938 1.4986)
			(layers "F.Cu" "F.Mask" "F.Paste")
			(net "M_E_CPU0_SA_DQ<17>")
		)
		(pad "32" smd rect
			(at -2.050034 -36.975034 270)
			(size 0.519938 1.4986)
			(layers "F.Cu" "F.Mask" "F.Paste")
			(net "GND")
		)
		(pad "33" smd rect
			(at -2.050034 -36.124896 270)
			(size 0.519938 1.4986)
			(layers "F.Cu" "F.Mask" "F.Paste")
			(net "M_E_CPU0_SA_DQS_DP<2>")
		)
		(pad "34" smd rect
			(at -2.050034 -35.275012 270)
			(size 0.519938 1.4986)
			(layers "F.Cu" "F.Mask" "F.Paste")
			(net "M_E_CPU0_SA_DQS_DN<2>")
		)
		(pad "35" smd rect
			(at -2.050034 -34.425128 270)
			(size 0.519938 1.4986)
			(layers "F.Cu" "F.Mask" "F.Paste")
			(net "GND")
		)
		(pad "36" smd rect
			(at -2.050034 -33.57499 270)
			(size 0.519938 1.4986)
			(layers "F.Cu" "F.Mask" "F.Paste")
			(net "M_E_CPU0_SA_DQ<20>")
		)
		(pad "37" smd rect
			(at -2.050034 -32.725106 270)
			(size 0.519938 1.4986)
			(layers "F.Cu" "F.Mask" "F.Paste")
			(net "GND")
		)
		(pad "38" smd rect
			(at -2.050034 -31.874968 270)
			(size 0.519938 1.4986)
			(layers "F.Cu" "F.Mask" "F.Paste")
			(net "M_E_CPU0_SA_DQ<21>")
		)
		(pad "39" smd rect
			(at -2.050034 -31.025084 270)
			(size 0.519938 1.4986)
			(layers "F.Cu" "F.Mask" "F.Paste")
			(net "GND")
		)
		(pad "40" smd rect
			(at -2.050034 -30.174946 270)
			(size 0.519938 1.4986)
			(layers "F.Cu" "F.Mask" "F.Paste")
			(net "M_E_CPU0_SA_DQ<24>")
		)
		(pad "41" smd rect
			(at -2.050034 -29.325062 270)
			(size 0.519938 1.4986)
			(layers "F.Cu" "F.Mask" "F.Paste")
			(net "GND")
		)
		(pad "42" smd rect
			(at -2.050034 -28.474924 270)
			(size 0.519938 1.4986)
			(layers "F.Cu" "F.Mask" "F.Paste")
			(net "M_E_CPU0_SA_DQ<25>")
		)
		(pad "43" smd rect
			(at -2.050034 -27.62504 270)
			(size 0.519938 1.4986)
			(layers "F.Cu" "F.Mask" "F.Paste")
			(net "GND")
		)
		(pad "44" smd rect
			(at -2.050034 -26.774902 270)
			(size 0.519938 1.4986)
			(layers "F.Cu" "F.Mask" "F.Paste")
			(net "M_E_CPU0_SA_DQS_DP<3>")
		)
		(pad "45" smd rect
			(at -2.050034 -25.925018 270)
			(size 0.519938 1.4986)
			(layers "F.Cu" "F.Mask" "F.Paste")
			(net "M_E_CPU0_SA_DQS_DN<3>")
		)
		(pad "46" smd rect
			(at -2.050034 -25.07488 270)
			(size 0.519938 1.4986)
			(layers "F.Cu" "F.Mask" "F.Paste")
			(net "GND")
		)
		(pad "47" smd rect
			(at -2.050034 -24.224996 270)
			(size 0.519938 1.4986)
			(layers "F.Cu" "F.Mask" "F.Paste")
			(net "M_E_CPU0_SA_DQ<28>")
		)
		(pad "48" smd rect
			(at -2.050034 -23.375112 270)
			(size 0.519938 1.4986)
			(layers "F.Cu" "F.Mask" "F.Paste")
			(net "GND")
		)
		(pad "49" smd rect
			(at -2.050034 -22.524974 270)
			(size 0.519938 1.4986)
			(layers "F.Cu" "F.Mask" "F.Paste")
			(net "M_E_CPU0_SA_DQ<29>")
		)
		(pad "50" smd rect
			(at -2.050034 -21.67509 270)
			(size 0.519938 1.4986)
			(layers "F.Cu" "F.Mask" "F.Paste")
			(net "GND")
		)
		(pad "51" smd rect
			(at -2.050034 -20.824952 270)
			(size 0.519938 1.4986)
			(layers "F.Cu" "F.Mask" "F.Paste")
			(net "M_E_CPU0_SA_CB<0>")
		)
		(pad "52" smd rect
			(at -2.050034 -19.975068 270)
			(size 0.519938 1.4986)
			(layers "F.Cu" "F.Mask" "F.Paste")
			(net "GND")
		)
		(pad "53" smd rect
			(at -2.050034 -19.12493 270)
			(size 0.519938 1.4986)
			(layers "F.Cu" "F.Mask" "F.Paste")
			(net "M_E_CPU0_SA_CB<1>")
		)
		(pad "54" smd rect
			(at -2.050034 -18.275046 270)
			(size 0.519938 1.4986)
			(layers "F.Cu" "F.Mask" "F.Paste")
			(net "GND")
		)
		(pad "55" smd rect
			(at -2.050034 -17.424908 270)
			(size 0.519938 1.4986)
			(layers "F.Cu" "F.Mask" "F.Paste")
			(net "M_E_CPU0_SA_DQS_DP<4>")
		)
		(pad "56" smd rect
			(at -2.050034 -16.575024 270)
			(size 0.519938 1.4986)
			(layers "F.Cu" "F.Mask" "F.Paste")
			(net "M_E_CPU0_SA_DQS_DN<4>")
		)
		(pad "57" smd rect
			(at -2.050034 -15.724886 270)
			(size 0.519938 1.4986)
			(layers "F.Cu" "F.Mask" "F.Paste")
			(net "GND")
		)
		(pad "58" smd rect
			(at -2.050034 -14.875002 270)
			(size 0.519938 1.4986)
			(layers "F.Cu" "F.Mask" "F.Paste")
			(net "M_E_CPU0_SA_CB<4>")
		)
		(pad "59" smd rect
			(at -2.050034 -14.025118 270)
			(size 0.519938 1.4986)
			(layers "F.Cu" "F.Mask" "F.Paste")
			(net "GND")
		)
		(pad "60" smd rect
			(at -2.050034 -13.17498 270)
			(size 0.519938 1.4986)
			(layers "F.Cu" "F.Mask" "F.Paste")
			(net "M_E_CPU0_SA_CB<5>")
		)
		(pad "61" smd rect
			(at -2.050034 -12.325096 270)
			(size 0.519938 1.4986)
			(layers "F.Cu" "F.Mask" "F.Paste")
			(net "GND")
		)
		(pad "62" smd rect
			(at -2.050034 -11.474958 270)
			(size 0.519938 1.4986)
			(layers "F.Cu" "F.Mask" "F.Paste")
			(net "M_E_CPU0_ALERT_N")
		)
		(pad "63" smd rect
			(at -2.050034 -10.625074 270)
			(size 0.519938 1.4986)
			(layers "F.Cu" "F.Mask" "F.Paste")
			(net "GND")
		)
		(pad "64" smd rect
			(at -2.050034 -9.774936 270)
			(size 0.519938 1.4986)
			(layers "F.Cu" "F.Mask" "F.Paste")
			(net "M_E_CPU0_SA_CS_N<2>")
		)
		(pad "65" smd rect
			(at -2.050034 -8.925052 270)
			(size 0.519938 1.4986)
			(layers "F.Cu" "F.Mask" "F.Paste")
			(net "GND")
		)
		(pad "66" smd rect
			(at -2.050034 -8.074914 270)
			(size 0.519938 1.4986)
			(layers "F.Cu" "F.Mask" "F.Paste")
			(net "M_E_CPU0_SA_CA<0>")
		)
		(pad "67" smd rect
			(at -2.050034 -7.22503 270)
			(size 0.519938 1.4986)
			(layers "F.Cu" "F.Mask" "F.Paste")
			(net "GND")
		)
		(pad "68" smd rect
			(at -2.050034 -6.374892 270)
			(size 0.519938 1.4986)
			(layers "F.Cu" "F.Mask" "F.Paste")
			(net "M_E_CPU0_SA_CA<2>")
		)
		(pad "69" smd rect
			(at -2.050034 -5.525008 270)
			(size 0.519938 1.4986)
			(layers "F.Cu" "F.Mask" "F.Paste")
			(net "GND")
		)
		(pad "70" smd rect
			(at -2.050034 -4.675124 270)
			(size 0.519938 1.4986)
			(layers "F.Cu" "F.Mask" "F.Paste")
			(net "M_E_CPU0_SA_CA<4>")
		)
		(pad "71" smd rect
			(at -2.050034 -3.824986 270)
			(size 0.519938 1.4986)
			(layers "F.Cu" "F.Mask" "F.Paste")
			(net "GND")
		)
		(pad "72" smd rect
			(at -2.050034 -2.975102 270)
			(size 0.519938 1.4986)
			(layers "F.Cu" "F.Mask" "F.Paste")
			(net "M_E_CPU0_SA_CA<6>")
		)
		(pad "73" smd rect
			(at -2.050034 -2.124964 270)
			(size 0.519938 1.4986)
			(layers "F.Cu" "F.Mask" "F.Paste")
			(net "GND")
		)
		(pad "74" smd rect
			(at -2.050034 -1.27508 270)
			(size 0.519938 1.4986)
			(layers "F.Cu" "F.Mask" "F.Paste")
			(net "M_E_CPU0_SA_PAR")
		)
		(pad "75" smd rect
			(at -2.050034 -0.424942 270)
			(size 0.519938 1.4986)
			(layers "F.Cu" "F.Mask" "F.Paste")
			(net "GND")
		)
		(pad "76" smd rect
			(at -2.050034 5.525008 270)
			(size 0.519938 1.4986)
			(layers "F.Cu" "F.Mask" "F.Paste")
			(net "M_E_CPU0_SB_CA<0>")
		)
		(pad "77" smd rect
			(at -2.050034 6.374892 270)
			(size 0.519938 1.4986)
			(layers "F.Cu" "F.Mask" "F.Paste")
			(net "GND")
		)
		(pad "78" smd rect
			(at -2.050034 7.22503 270)
			(size 0.519938 1.4986)
			(layers "F.Cu" "F.Mask" "F.Paste")
			(net "M_E_CPU0_SB_CA<2>")
		)
		(pad "79" smd rect
			(at -2.050034 8.074914 270)
			(size 0.519938 1.4986)
			(layers "F.Cu" "F.Mask" "F.Paste")
			(net "GND")
		)
		(pad "80" smd rect
			(at -2.050034 8.925052 270)
			(size 0.519938 1.4986)
			(layers "F.Cu" "F.Mask" "F.Paste")
			(net "M_E_CPU0_SB_CA<4>")
		)
		(pad "81" smd rect
			(at -2.050034 9.774936 270)
			(size 0.519938 1.4986)
			(layers "F.Cu" "F.Mask" "F.Paste")
			(net "GND")
		)
		(pad "82" smd rect
			(at -2.050034 10.625074 270)
			(size 0.519938 1.4986)
			(layers "F.Cu" "F.Mask" "F.Paste")
			(net "M_E_CPU0_SB_CA<6>")
		)
		(pad "83" smd rect
			(at -2.050034 11.474958 270)
			(size 0.519938 1.4986)
			(layers "F.Cu" "F.Mask" "F.Paste")
			(net "GND")
		)
		(pad "84" smd rect
			(at -2.050034 12.325096 270)
			(size 0.519938 1.4986)
			(layers "F.Cu" "F.Mask" "F.Paste")
			(net "M_E_CPU0_SB_CS_N<2>")
		)
		(pad "85" smd rect
			(at -2.050034 13.17498 270)
			(size 0.519938 1.4986)
			(layers "F.Cu" "F.Mask" "F.Paste")
			(net "GND")
		)
		(pad "86" smd rect
			(at -2.050034 14.025118 270)
			(size 0.519938 1.4986)
			(layers "F.Cu" "F.Mask" "F.Paste")
			(net "M_E_CPU0_SA_RSP<1>")
		)
		(pad "87" smd rect
			(at -2.050034 14.875002 270)
			(size 0.519938 1.4986)
			(layers "F.Cu" "F.Mask" "F.Paste")
			(net "M_E_CPU0_SB_RSP<1>")
		)
		(pad "88" smd rect
			(at -2.050034 15.724886 270)
			(size 0.519938 1.4986)
			(layers "F.Cu" "F.Mask" "F.Paste")
			(net "GND")
		)
		(pad "89" smd rect
			(at -2.050034 16.575024 270)
			(size 0.519938 1.4986)
			(layers "F.Cu" "F.Mask" "F.Paste")
			(net "M_E_CPU0_SB_CB<4>")
		)
		(pad "90" smd rect
			(at -2.050034 17.424908 270)
			(size 0.519938 1.4986)
			(layers "F.Cu" "F.Mask" "F.Paste")
			(net "GND")
		)
		(pad "91" smd rect
			(at -2.050034 18.275046 270)
			(size 0.519938 1.4986)
			(layers "F.Cu" "F.Mask" "F.Paste")
			(net "M_E_CPU0_SB_CB<5>")
		)
		(pad "92" smd rect
			(at -2.050034 19.12493 270)
			(size 0.519938 1.4986)
			(layers "F.Cu" "F.Mask" "F.Paste")
			(net "GND")
		)
		(pad "93" smd rect
			(at -2.050034 19.975068 270)
			(size 0.519938 1.4986)
			(layers "F.Cu" "F.Mask" "F.Paste")
			(net "M_E_CPU0_SB_DQS_DP<9>")
		)
		(pad "94" smd rect
			(at -2.050034 20.824952 270)
			(size 0.519938 1.4986)
			(layers "F.Cu" "F.Mask" "F.Paste")
			(net "M_E_CPU0_SB_DQS_DN<9>")
		)
		(pad "95" smd rect
			(at -2.050034 21.67509 270)
			(size 0.519938 1.4986)
			(layers "F.Cu" "F.Mask" "F.Paste")
			(net "GND")
		)
		(pad "96" smd rect
			(at -2.050034 22.524974 270)
			(size 0.519938 1.4986)
			(layers "F.Cu" "F.Mask" "F.Paste")
			(net "M_E_CPU0_SB_CB<0>")
		)
		(pad "97" smd rect
			(at -2.050034 23.375112 270)
			(size 0.519938 1.4986)
			(layers "F.Cu" "F.Mask" "F.Paste")
			(net "GND")
		)
		(pad "98" smd rect
			(at -2.050034 24.224996 270)
			(size 0.519938 1.4986)
			(layers "F.Cu" "F.Mask" "F.Paste")
			(net "M_E_CPU0_SB_CB<1>")
		)
		(pad "99" smd rect
			(at -2.050034 25.07488 270)
			(size 0.519938 1.4986)
			(layers "F.Cu" "F.Mask" "F.Paste")
			(net "GND")
		)
		(pad "100" smd rect
			(at -2.050034 25.925018 270)
			(size 0.519938 1.4986)
			(layers "F.Cu" "F.Mask" "F.Paste")
			(net "M_E_CPU0_SB_DQ<0>")
		)
		(pad "101" smd rect
			(at -2.050034 26.774902 270)
			(size 0.519938 1.4986)
			(layers "F.Cu" "F.Mask" "F.Paste")
			(net "GND")
		)
		(pad "102" smd rect
			(at -2.050034 27.62504 270)
			(size 0.519938 1.4986)
			(layers "F.Cu" "F.Mask" "F.Paste")
			(net "M_E_CPU0_SB_DQ<1>")
		)
		(pad "103" smd rect
			(at -2.050034 28.474924 270)
			(size 0.519938 1.4986)
			(layers "F.Cu" "F.Mask" "F.Paste")
			(net "GND")
		)
		(pad "104" smd rect
			(at -2.050034 29.325062 270)
			(size 0.519938 1.4986)
			(layers "F.Cu" "F.Mask" "F.Paste")
			(net "M_E_CPU0_SB_DQS_DP<0>")
		)
		(pad "105" smd rect
			(at -2.050034 30.174946 270)
			(size 0.519938 1.4986)
			(layers "F.Cu" "F.Mask" "F.Paste")
			(net "M_E_CPU0_SB_DQS_DN<0>")
		)
		(pad "106" smd rect
			(at -2.050034 31.025084 270)
			(size 0.519938 1.4986)
			(layers "F.Cu" "F.Mask" "F.Paste")
			(net "GND")
		)
		(pad "107" smd rect
			(at -2.050034 31.874968 270)
			(size 0.519938 1.4986)
			(layers "F.Cu" "F.Mask" "F.Paste")
			(net "M_E_CPU0_SB_DQ<4>")
		)
		(pad "108" smd rect
			(at -2.050034 32.725106 270)
			(size 0.519938 1.4986)
			(layers "F.Cu" "F.Mask" "F.Paste")
			(net "GND")
		)
		(pad "109" smd rect
			(at -2.050034 33.57499 270)
			(size 0.519938 1.4986)
			(layers "F.Cu" "F.Mask" "F.Paste")
			(net "M_E_CPU0_SB_DQ<5>")
		)
		(pad "110" smd rect
			(at -2.050034 34.425128 270)
			(size 0.519938 1.4986)
			(layers "F.Cu" "F.Mask" "F.Paste")
			(net "GND")
		)
		(pad "111" smd rect
			(at -2.050034 35.275012 270)
			(size 0.519938 1.4986)
			(layers "F.Cu" "F.Mask" "F.Paste")
			(net "M_E_CPU0_SB_DQ<8>")
		)
		(pad "112" smd rect
			(at -2.050034 36.124896 270)
			(size 0.519938 1.4986)
			(layers "F.Cu" "F.Mask" "F.Paste")
			(net "GND")
		)
	)
)
